# BASEBOARD_FAB2 (Tioga Pass) — schematic netlist excerpt (pin names and nets, part order shuffled) for the footprints in the layout excerpt that follows; sources: Cadence DE-HDL packaged netlist, KiCad conversion of Wiwynn_Tioga_Pass_MB.brd

J25W1  SMC-CON13-GP  pkg CONN-GC2  page 252
  \1\  = V_IO_R_J
  \2\  = GND
  \3\  = V_IO_G_J
  \4\  = GND
  \5\  = V_IO_B_J
  \6\  = GND
  \7\  = V_IO_VSYNC_J
  \8\  = GND
  \9\  = V_IO_HSYNC_J
  \10\  = GND
  \11\  = V_IBMC_5V_DDC_SDA_J
  \12\  = V_IBMC_5V_DDC_SCL_J
  \13\  = P5V_VGA
  PTH1  = GND
  PTH2  = GND

(kicad_pcb
	(version 20260206)
	(generator "pcbnew")
	(generator_version "10.0")
	(general
		(thickness 1.6)
		(legacy_teardrops no)
	)
	(paper "A4")
	(title_block
		(title "Wiwynn_Tioga_Pass_MB.brd")
		(comment 1 "Tioga Pass / footprints 193-193 of 4770")
	)
	(layers
		(0 "F.Cu" signal "TOP")
		(4 "In1.Cu" signal "L2GND")
		(6 "In2.Cu" signal "L3")
		(8 "In3.Cu" signal "L4GND")
		(10 "In4.Cu" signal "L5")
		(12 "In5.Cu" signal "L6GND")
		(14 "In6.Cu" signal "L7VCC")
		(16 "In7.Cu" signal "L8VCC")
		(18 "In8.Cu" signal "L9GND")
		(20 "In9.Cu" signal "L10")
		(22 "In10.Cu" signal "L11GND")
		(24 "In11.Cu" signal "L12")
		(26 "In12.Cu" signal "L13GND")
		(2 "B.Cu" signal "BOTTOM")
		(9 "F.Adhes" user "F.Adhesive")
		(11 "B.Adhes" user "B.Adhesive")
		(13 "F.Paste" user "Package Geometry/Pastemask Top")
		(15 "B.Paste" user "Package Geometry/Pastemask Bottom")
		(5 "F.SilkS" user "Ref Des/Silkscreen Top")
		(7 "B.SilkS" user "Ref Des/Silkscreen Bottom")
		(1 "F.Mask" user "Board Geometry/Soldermask Top")
		(3 "B.Mask" user "Board Geometry/Soldermask Bottom")
		(17 "Dwgs.User" user "User.Drawings")
		(19 "Cmts.User" user "User.Comments")
		(21 "Eco1.User" user "User.Eco1")
		(23 "Eco2.User" user "User.Eco2")
		(25 "Edge.Cuts" user "Board Geometry/Outline")
		(27 "Margin" user)
		(31 "F.CrtYd" user "Package Geometry/Place Bound Top")
		(29 "B.CrtYd" user "Package Geometry/Place Bound Bottom")
		(35 "F.Fab" user "Ref Des/Assembly Top")
		(33 "B.Fab" user "Ref Des/Assembly Bottom")
	)
	(footprint ""
		(layer "F.Cu")
		(at 500.579898 -42.61993 90)
		(property "Reference" "J25W1"
			(at 0 0 90)
			(layer "F.SilkS")
			(hide yes)
			(effects
				(font
					(size 1.27 1.27)
				)
			)
		)
		(property "Value" "*"
			(at 4.3434 -6.4643 90)
			(unlocked yes)
			(layer "F.Fab")
			(hide yes)
			(effects
				(font
					(size 1.27 1.016)
					(thickness 0.1524)
				)
			)
		)
		(property "Device Type" "SMC-CON13-GP_CONN-GC2-SMC-CON1A"
			(at 4.3434 -7.9883 90)
			(unlocked yes)
			(layer "F.Fab")
			(hide yes)
			(effects
				(font
					(size 1.27 1.016)
					(thickness 0.1524)
				)
			)
		)
		(duplicate_pad_numbers_are_jumpers no)
		(fp_line
			(start -6.6548 -5.0038)
			(end -5.7023 -5.0038)
			(stroke
				(width 0.3302)
				(type default)
			)
			(layer "F.SilkS")
		)
		(fp_line
			(start 6.5659 -4.9149)
			(end 6.5659 -3.7973)
			(stroke
				(width 0.1524)
				(type default)
			)
			(layer "F.SilkS")
		)
		(fp_line
			(start -6.5659 -4.9149)
			(end 6.5659 -4.9149)
			(stroke
				(width 0.1524)
				(type default)
			)
			(layer "F.SilkS")
		)
		(fp_line
			(start -6.6548 -3.8989)
			(end -6.6548 -5.0038)
			(stroke
				(width 0.3302)
				(type default)
			)
			(layer "F.SilkS")
		)
		(fp_line
			(start 7.9629 -3.7973)
			(end 7.9629 1.1557)
			(stroke
				(width 0.1524)
				(type default)
			)
			(layer "F.SilkS")
		)
		(fp_line
			(start 6.5659 -3.7973)
			(end 7.9629 -3.7973)
			(stroke
				(width 0.1524)
				(type default)
			)
			(layer "F.SilkS")
		)
		(fp_line
			(start -6.5659 -3.7973)
			(end -6.5659 -4.9149)
			(stroke
				(width 0.1524)
				(type default)
			)
			(layer "F.SilkS")
		)
		(fp_line
			(start -7.9629 -3.7973)
			(end -6.5659 -3.7973)
			(stroke
				(width 0.1524)
				(type default)
			)
			(layer "F.SilkS")
		)
		(fp_line
			(start 7.9629 1.1557)
			(end -7.9629 1.1557)
			(stroke
				(width 0.1524)
				(type default)
			)
			(layer "F.SilkS")
		)
		(fp_line
			(start -7.9629 1.1557)
			(end -7.9629 -3.7973)
			(stroke
				(width 0.1524)
				(type default)
			)
			(layer "F.SilkS")
		)
		(fp_poly
			(pts
				(xy -6.052312 -4.930902) (xy -5.428488 -5.554726) (xy -6.676136 -5.554726)
			)
			(stroke
				(width 0)
				(type default)
			)
			(fill yes)
			(layer "F.SilkS")
		)
		(fp_poly
			(pts
				(xy -6.69036 -2.897124) (xy -6.69036 1.1684) (xy 6.69036 1.1684) (xy 6.69036 -2.897124)
			)
			(stroke
				(width 0)
				(type default)
			)
			(fill yes)
			(layer "F.SilkS")
		)
		(fp_poly
			(pts
				(xy -7.5057 0.6985) (xy -7.5057 -3.5433) (xy -6.096 -3.5433) (xy -6.096 -4.2545) (xy 6.096 -4.2545)
				(xy 6.096 -3.5433) (xy 7.5057 -3.5433) (xy 7.5057 0.6985)
			)
			(stroke
				(width 0)
				(type default)
			)
			(fill no)
			(layer "F.CrtYd")
		)
		(fp_poly
			(pts
				(xy -8.2169 1.4097) (xy -8.2169 -4.0513) (xy -6.8199 -4.0513) (xy -6.8199 -5.1689) (xy 6.8199 -5.1689)
				(xy 6.8199 -4.0513) (xy 8.2169 -4.0513) (xy 8.2169 -0.00635) (xy 7.5057 -0.00635) (xy 7.5057 -3.5433)
				(xy 6.096 -3.5433) (xy 6.096 -4.2545) (xy -6.096 -4.2545) (xy -6.096 -3.5433) (xy -7.5057 -3.5433)
				(xy -7.5057 0.6985) (xy 7.5057 0.6985) (xy 7.5057 0.00635) (xy 8.2169 0.00635) (xy 8.2169 1.4097)
			)
			(stroke
				(width 0)
				(type default)
			)
			(fill no)
			(layer "F.CrtYd")
		)
		(fp_poly
			(pts
				(xy -8.2169 1.4097) (xy -8.2169 -4.0513) (xy -6.8199 -4.0513) (xy -6.8199 -5.1689) (xy 6.8199 -5.1689)
				(xy 6.8199 -4.0513) (xy 8.2169 -4.0513) (xy 8.2169 1.4097)
			)
			(stroke
				(width 0)
				(type default)
			)
			(fill no)
			(layer "F.Fab")
		)
		(pad "1" smd rect
			(at -5.999988 -3.875024 90)
			(size 0.6096 1.5494)
			(layers "F.Cu" "F.Mask" "F.Paste")
			(net "V_IO_R_J")
		)
		(pad "2" smd rect
			(at -4.99999 -3.875024 90)
			(size 0.6096 1.5494)
			(layers "F.Cu" "F.Mask" "F.Paste")
			(net "GND")
		)
		(pad "3" smd rect
			(at -3.999992 -3.875024 90)
			(size 0.6096 1.5494)
			(layers "F.Cu" "F.Mask" "F.Paste")
			(net "V_IO_G_J")
		)
		(pad "4" smd rect
			(at -2.999994 -3.875024 90)
			(size 0.6096 1.5494)
			(layers "F.Cu" "F.Mask" "F.Paste")
			(net "GND")
		)
		(pad "5" smd rect
			(at -1.999996 -3.875024 90)
			(size 0.6096 1.5494)
			(layers "F.Cu" "F.Mask" "F.Paste")
			(net "V_IO_B_J")
		)
		(pad "6" smd rect
			(at -0.999998 -3.875024 90)
			(size 0.6096 1.5494)
			(layers "F.Cu" "F.Mask" "F.Paste")
			(net "GND")
		)
		(pad "7" smd rect
			(at 0 -3.875024 90)
			(size 0.6096 1.5494)
			(layers "F.Cu" "F.Mask" "F.Paste")
			(net "V_IO_VSYNC_J")
		)
		(pad "8" smd rect
			(at 0.999998 -3.875024 90)
			(size 0.6096 1.5494)
			(layers "F.Cu" "F.Mask" "F.Paste")
			(net "GND")
		)
		(pad "9" smd rect
			(at 1.999996 -3.875024 90)
			(size 0.6096 1.5494)
			(layers "F.Cu" "F.Mask" "F.Paste")
			(net "V_IO_HSYNC_J")
		)
		(pad "10" smd rect
			(at 2.999994 -3.875024 90)
			(size 0.6096 1.5494)
			(layers "F.Cu" "F.Mask" "F.Paste")
			(net "GND")
		)
		(pad "11" smd rect
			(at 3.999992 -3.875024 90)
			(size 0.6096 1.5494)
			(layers "F.Cu" "F.Mask" "F.Paste")
			(net "V_IBMC_5V_DDC_SDA_J")
		)
		(pad "12" smd rect
			(at 4.99999 -3.875024 90)
			(size 0.6096 1.5494)
			(layers "F.Cu" "F.Mask" "F.Paste")
			(net "V_IBMC_5V_DDC_SCL_J")
		)
		(pad "13" smd rect
			(at 5.999988 -3.875024 90)
			(size 0.6096 1.5494)
			(layers "F.Cu" "F.Mask" "F.Paste")
			(net "P5V_VGA")
		)
		(pad "PTH1" smd rect
			(at -7.29996 0 90)
			(size 0.8128 1.8034)
			(layers "F.Cu" "F.Mask" "F.Paste")
			(net "GND")
		)
		(pad "PTH2" smd rect
			(at 7.29996 0 90)
			(size 0.8128 1.8034)
			(layers "F.Cu" "F.Mask" "F.Paste")
			(net "GND")
		)
	)
)
